FILE_TYPE = CONNECTIVITY;
{Allegro Design Entry HDL 17.4-2019 S026 (4007227) 1/17/2022}
"PAGE_NUMBER" = 196;
0"NC";
END.
